# TIMECARD (Time Appliance Project (Time Card)) — schematic netlist excerpt (pin names and nets, part order shuffled) for the footprints in the layout excerpt that follows; sources: Cadence DE-HDL packaged netlist, KiCad conversion of R4006-B0001-02_R01.brd

C174  CAPACITOR  100UF 6.3V 20%  pkg SMC_1210R_H110  page 14 : \1\ = XP3R3V_FPGA ; \2\ = SG
TP34  TP_PIONT  pkg TP010CT020B030_PTH  page 25 : \1\ = SMA3_SIG_OUT_BF_EN_N

(kicad_pcb
	(version 20260206)
	(generator "pcbnew")
	(generator_version "10.0")
	(general
		(thickness 1.6)
		(legacy_teardrops no)
	)
	(paper "A4")
	(title_block
		(title "timecard-production-celestica-r4006 — R4006-B0001-02_R01.brd")
		(comment 1 "Time Appliance Project (Time Card) / footprints 85-86 of 1113")
	)
	(layers
		(0 "F.Cu" signal "TOP")
		(4 "In1.Cu" signal "L02_GND1")
		(6 "In2.Cu" signal "L03_SIG1")
		(8 "In3.Cu" signal "L04_GND2")
		(10 "In4.Cu" signal "L05_VCC1")
		(12 "In5.Cu" signal "L06_VCC2")
		(14 "In6.Cu" signal "L07_GND3")
		(16 "In7.Cu" signal "L08_SIG2")
		(18 "In8.Cu" signal "L09_GND4")
		(2 "B.Cu" signal "BOTTOM")
		(9 "F.Adhes" user "F.Adhesive")
		(11 "B.Adhes" user "B.Adhesive")
		(13 "F.Paste" user "Package Geometry/Pastemask Top")
		(15 "B.Paste" user "Package Geometry/Pastemask Bottom")
		(5 "F.SilkS" user "Ref Des/Silkscreen Top")
		(7 "B.SilkS" user "Ref Des/Silkscreen Bottom")
		(1 "F.Mask" user "Board Geometry/Soldermask Top")
		(3 "B.Mask" user "Board Geometry/Soldermask Bottom")
		(17 "Dwgs.User" user "User.Drawings")
		(19 "Cmts.User" user "User.Comments")
		(21 "Eco1.User" user "User.Eco1")
		(23 "Eco2.User" user "User.Eco2")
		(25 "Edge.Cuts" user "Board Geometry/Outline")
		(27 "Margin" user)
		(31 "F.CrtYd" user "Package Geometry/Place Bound Top")
		(29 "B.CrtYd" user "Package Geometry/Place Bound Bottom")
		(35 "F.Fab" user "Ref Des/Assembly Top")
		(33 "B.Fab" user "Ref Des/Assembly Bottom")
	)
	(footprint ""
		(layer "F.Cu")
		(at 120.396 -63.2206 90)
		(property "Reference" "C174"
			(at 3.8354 0.16637 90)
			(unlocked yes)
			(layer "F.SilkS")
			(effects
				(font
					(size 0.7874 0.5842)
					(thickness 0.1524)
				)
			)
		)
		(property "Value" "VAL*"
			(at 0.1016 3.769106 90)
			(unlocked yes)
			(layer "F.Fab")
			(hide yes)
			(effects
				(font
					(size 0.7874 0.5842)
					(thickness 0.1524)
				)
			)
		)
		(property "Device Type" "CAPACITOR-G109-0G107-BM,100UF,A"
			(at 0.0762 2.829306 90)
			(unlocked yes)
			(layer "F.Fab")
			(hide yes)
			(effects
				(font
					(size 0.7874 0.5842)
					(thickness 0.1524)
				)
			)
		)
		(property "User Part Number" "PARTNUM*"
			(at 0.2032 5.801106 90)
			(unlocked yes)
			(layer "Cmts.User")
			(hide yes)
			(effects
				(font
					(size 0.7874 0.5842)
					(thickness 0.1524)
				)
			)
		)
		(property "Tolerance" "TOL*"
			(at 0.127 4.734306 90)
			(unlocked yes)
			(layer "Cmts.User")
			(hide yes)
			(effects
				(font
					(size 0.7874 0.5842)
					(thickness 0.1524)
				)
			)
		)
		(duplicate_pad_numbers_are_jumpers no)
		(fp_line
			(start 2.159 -1.5748)
			(end 2.159 1.5748)
			(stroke
				(width 0.1)
				(type default)
			)
			(layer "F.SilkS")
		)
		(fp_line
			(start -2.159 -1.5748)
			(end 2.159 -1.5748)
			(stroke
				(width 0.1)
				(type default)
			)
			(layer "F.SilkS")
		)
		(fp_line
			(start 2.159 1.5748)
			(end -2.159 1.5748)
			(stroke
				(width 0.1)
				(type default)
			)
			(layer "F.SilkS")
		)
		(fp_line
			(start -2.159 1.5748)
			(end -2.159 -1.5748)
			(stroke
				(width 0.1)
				(type default)
			)
			(layer "F.SilkS")
		)
		(fp_rect
			(start -2.159 -1.5748)
			(end 2.159 1.5748)
			(stroke
				(width 0)
				(type default)
			)
			(fill no)
			(layer "F.CrtYd")
		)
		(fp_line
			(start 1.6002 -1.2446)
			(end -1.6002 -1.2446)
			(stroke
				(width 0.1)
				(type default)
			)
			(layer "F.Fab")
		)
		(fp_line
			(start -1.6002 -1.2446)
			(end -1.6002 1.2446)
			(stroke
				(width 0.1)
				(type default)
			)
			(layer "F.Fab")
		)
		(fp_line
			(start 1.6002 1.2446)
			(end 1.6002 -1.2446)
			(stroke
				(width 0.1)
				(type default)
			)
			(layer "F.Fab")
		)
		(fp_line
			(start -1.6002 1.2446)
			(end 1.6002 1.2446)
			(stroke
				(width 0.1)
				(type default)
			)
			(layer "F.Fab")
		)
		(pad "1" smd rect
			(at -1.3335 0 90)
			(size 1.143 2.6416)
			(layers "F.Cu" "F.Mask" "F.Paste")
			(net "XP3R3V_FPGA")
		)
		(pad "2" smd rect
			(at 1.3335 0 90)
			(size 1.143 2.6416)
			(layers "F.Cu" "F.Mask" "F.Paste")
			(net "SG")
		)
		(zone
			(layer "F.Cu")
			(hatch none 0.5)
			(connect_pads
				(clearance 0)
			)
			(min_thickness 0.25)
			(keepout
				(tracks allowed)
				(vias not_allowed)
				(pads allowed)
				(copperpour not_allowed)
				(footprints allowed)
			)
			(placement
				(enabled no)
				(sheetname "")
			)
			(fill
				(thermal_gap 0.5)
				(thermal_bridge_width 0.5)
				(island_removal_mode 0)
			)
			(polygon
				(pts
					(xy 118.999 -62.5348) (xy 121.793 -62.5348) (xy 121.793 -63.9064) (xy 118.999 -63.9064)
				)
			)
		)
	)
	(footprint ""
		(layer "F.Cu")
		(at 16.383 -32.893)
		(property "Reference" "TP34"
			(at 1.69037 2.9972 90)
			(unlocked yes)
			(layer "F.SilkS")
			(effects
				(font
					(size 0.7874 0.5842)
					(thickness 0.1524)
				)
				(justify left)
			)
		)
		(property "Value" ""
			(at 0 0 0)
			(layer "F.Fab")
			(effects
				(font
					(size 1.27 1.27)
				)
			)
		)
		(property "Device Type" "TP_PIONT-TP010CT020B030_PTH-TPA"
			(at -1.341882 0.996696 0)
			(unlocked yes)
			(layer "F.Fab")
			(hide yes)
			(effects
				(font
					(size 0.7874 0.5842)
					(thickness 0.000001)
				)
				(justify left)
			)
		)
		(duplicate_pad_numbers_are_jumpers no)
		(fp_poly
			(pts
				(arc
					(start 0.889 0)
					(mid -0.889 0)
					(end 0.889 0)
				)
			)
			(stroke
				(width 0)
				(type default)
			)
			(fill no)
			(layer "B.CrtYd")
		)
		(fp_poly
			(pts
				(arc
					(start 0.889 0)
					(mid -0.889 0)
					(end 0.889 0)
				)
			)
			(stroke
				(width 0)
				(type default)
			)
			(fill no)
			(layer "F.CrtYd")
		)
		(pad "1" thru_hole circle
			(at 0 0)
			(size 0.508 0.508)
			(drill 0.254)
			(layers "*.Cu" "*.Mask")
			(remove_unused_layers no)
			(net "SMA3_SIG_OUT_BF_EN_N")
			(clearance 0.1016)
			(padstack
				(mode front_inner_back)
				(layer "Inner"
					(shape circle)
					(size 0.508 0.508)
					(clearance 0.1016)
				)
				(layer "B.Cu"
					(shape circle)
					(size 0.762 0.762)
					(clearance -0.0254)
				)
			)
		)
	)
)
